FILE_TYPE = CONNECTIVITY;
{Allegro Design Entry HDL 16.6-p007 (v16-6-112F) 10/10/2012}
"PAGE_NUMBER" = 66;
0"NC";
1"P3E_CPU1_PE3_MP_TXN<15:8>";
2"P3E_CPU1_PE3_MP_TXN<7:0>";
3"P3E_CPU1_PE3_MP_TXP<15:8>";
4"P3E_CPU1_PE3_MP_TXP<7:0>";
5"P3E_CPU1_PE3_MP_RXP<15:8>";
6"P3E_CPU1_PE3_MP_RXN<15:8>";
7"P3E_CPU1_PE3_MP_RXN<7:0>";
8"P3E_CPU1_PE3_MP_RXP<7:0>";
9"P3E_CPU1_PE3_MP_RXP<0>";
10"P3E_CPU1_PE3_MP_RXP<1>";
11"P3E_CPU1_PE3_MP_RXP<2>";
12"P3E_CPU1_PE3_MP_RXP<3>";
13"P3E_CPU1_PE3_MP_RXN<0>";
14"P3E_CPU1_PE3_MP_RXN<1>";
15"P3E_CPU1_PE3_MP_RXN<2>";
16"P3E_CPU1_PE3_MP_RXN<3>";
17"P3E_CPU1_PE3_MP_RXP<4>";
18"P3E_CPU1_PE3_MP_RXP<5>";
19"P3E_CPU1_PE3_MP_RXP<6>";
20"P3E_CPU1_PE3_MP_RXP<7>";
21"P3E_CPU1_PE3_MP_RXP<8>";
22"P3E_CPU1_PE3_MP_RXP<9>";
23"P3E_CPU1_PE3_MP_RXP<10>";
24"P3E_CPU1_PE3_MP_RXP<11>";
25"P3E_CPU1_PE3_MP_RXN<12>";
26"P3E_CPU1_PE3_MP_RXP<13>";
27"P3E_CPU1_PE3_MP_RXP<14>";
28"P3E_CPU1_PE3_MP_RXP<15>";
29"P3E_CPU1_PE3_MP_RXN<4>";
30"P3E_CPU1_PE3_MP_RXN<5>";
31"P3E_CPU1_PE3_MP_RXN<6>";
32"P3E_CPU1_PE3_MP_RXN<7>";
33"P3E_CPU1_PE3_MP_RXN<8>";
34"P3E_CPU1_PE3_MP_RXN<9>";
35"P3E_CPU1_PE3_MP_RXN<10>";
36"P3E_CPU1_PE3_MP_RXN<11>";
37"P3E_CPU1_PE3_MP_RXP<12>";
38"P3E_CPU1_PE3_MP_RXN<13>";
39"P3E_CPU1_PE3_MP_RXN<14>";
40"P3E_CPU1_PE3_MP_RXN<15>";
41"P3E_CPU1_PE3_MP_TXP<0>";
42"P3E_CPU1_PE3_MP_TXP<1>";
43"P3E_CPU1_PE3_MP_TXP<2>";
44"P3E_CPU1_PE3_MP_TXP<3>";
45"P3E_CPU1_PE3_MP_TXN<0>";
46"P3E_CPU1_PE3_MP_TXN<1>";
47"P3E_CPU1_PE3_MP_TXN<2>";
48"P3E_CPU1_PE3_MP_TXN<3>";
49"P3E_CPU1_PE3_MP_TXP<4>";
50"P3E_CPU1_PE3_MP_TXP<5>";
51"P3E_CPU1_PE3_MP_TXP<6>";
52"P3E_CPU1_PE3_MP_TXP<7>";
53"P3E_CPU1_PE3_MP_TXP<8>";
54"P3E_CPU1_PE3_MP_TXP<9>";
55"P3E_CPU1_PE3_MP_TXP<10>";
56"P3E_CPU1_PE3_MP_TXP<11>";
57"P3E_CPU1_PE3_MP_TXP<12>";
58"P3E_CPU1_PE3_MP_TXP<13>";
59"P3E_CPU1_PE3_MP_TXP<14>";
60"P3E_CPU1_PE3_MP_TXP<15>";
61"P3E_CPU1_PE3_MP_TXN<4>";
62"P3E_CPU1_PE3_MP_TXN<5>";
63"P3E_CPU1_PE3_MP_TXN<6>";
64"P3E_CPU1_PE3_MP_TXN<7>";
65"P3E_CPU1_PE3_MP_TXN<8>";
66"P3E_CPU1_PE3_MP_TXN<9>";
67"P3E_CPU1_PE3_MP_TXN<10>";
68"P3E_CPU1_PE3_MP_TXN<11>";
69"P3E_CPU1_PE3_MP_TXN<12>";
70"P3E_CPU1_PE3_MP_TXN<13>";
71"P3E_CPU1_PE3_MP_TXN<14>";
72"P3E_CPU1_PE3_MP_TXN<15>";
%"TAP"
"1","(-5550,1625)","2","mstr_standard","I10";
;
HDL_TAP"TRUE"
BODY_TYPE"PLUMBING"
CDS_LIB"mstr_standard";
"B \NAC \NWC"7;
"S \NAC"
BN"0"13;
%"TAP"
"1","(-5550,1675)","2","mstr_standard","I11";
;
HDL_TAP"TRUE"
BODY_TYPE"PLUMBING"
CDS_LIB"mstr_standard";
"B \NAC \NWC"7;
"S \NAC"
BN"1"14;
%"TAP"
"1","(-5550,1725)","2","mstr_standard","I12";
;
HDL_TAP"TRUE"
BODY_TYPE"PLUMBING"
CDS_LIB"mstr_standard";
"B \NAC \NWC"7;
"S \NAC"
BN"2"15;
%"TAP"
"1","(-5550,1775)","2","mstr_standard","I13";
;
HDL_TAP"TRUE"
BODY_TYPE"PLUMBING"
CDS_LIB"mstr_standard";
"B \NAC \NWC"7;
"S \NAC"
BN"3"16;
%"TAP"
"1","(-5400,1875)","2","mstr_standard","I14";
;
HDL_TAP"TRUE"
BODY_TYPE"PLUMBING"
CDS_LIB"mstr_standard";
"B \NAC \NWC"8;
"S \NAC"
BN"0"9;
%"TAP"
"1","(-5400,1925)","2","mstr_standard","I15";
;
HDL_TAP"TRUE"
BODY_TYPE"PLUMBING"
CDS_LIB"mstr_standard";
"B \NAC \NWC"8;
"S \NAC"
BN"1"10;
%"TAP"
"1","(-5400,1975)","2","mstr_standard","I16";
;
HDL_TAP"TRUE"
BODY_TYPE"PLUMBING"
CDS_LIB"mstr_standard";
"B \NAC \NWC"8;
"S \NAC"
BN"2"11;
%"TAP"
"1","(-5400,2025)","2","mstr_standard","I17";
;
HDL_TAP"TRUE"
BODY_TYPE"PLUMBING"
CDS_LIB"mstr_standard";
"B \NAC \NWC"8;
"S \NAC"
BN"3"12;
%"TAP"
"1","(-5550,2175)","2","mstr_standard","I18";
;
HDL_TAP"TRUE"
BODY_TYPE"PLUMBING"
CDS_LIB"mstr_standard";
"B \NAC \NWC"7;
"S \NAC"
BN"5"30;
%"TAP"
"1","(-5550,2125)","2","mstr_standard","I19";
;
HDL_TAP"TRUE"
BODY_TYPE"PLUMBING"
CDS_LIB"mstr_standard";
"B \NAC \NWC"7;
"S \NAC"
BN"4"29;
%"TAP"
"1","(-5550,2225)","2","mstr_standard","I20";
;
HDL_TAP"TRUE"
BODY_TYPE"PLUMBING"
CDS_LIB"mstr_standard";
"B \NAC \NWC"7;
"S \NAC"
BN"6"31;
%"TAP"
"1","(-5550,2275)","2","mstr_standard","I21";
;
HDL_TAP"TRUE"
BODY_TYPE"PLUMBING"
CDS_LIB"mstr_standard";
"B \NAC \NWC"7;
"S \NAC"
BN"7"32;
%"TAP"
"1","(-5400,2375)","2","mstr_standard","I22";
;
HDL_TAP"TRUE"
BODY_TYPE"PLUMBING"
CDS_LIB"mstr_standard";
"B \NAC \NWC"8;
"S \NAC"
BN"4"17;
%"TAP"
"1","(-5400,2425)","2","mstr_standard","I23";
;
HDL_TAP"TRUE"
BODY_TYPE"PLUMBING"
CDS_LIB"mstr_standard";
"B \NAC \NWC"8;
"S \NAC"
BN"5"18;
%"TAP"
"1","(-5400,2475)","2","mstr_standard","I24";
;
HDL_TAP"TRUE"
BODY_TYPE"PLUMBING"
CDS_LIB"mstr_standard";
"B \NAC \NWC"8;
"S \NAC"
BN"6"19;
%"TAP"
"1","(-5400,2525)","2","mstr_standard","I25";
;
HDL_TAP"TRUE"
BODY_TYPE"PLUMBING"
CDS_LIB"mstr_standard";
"B \NAC \NWC"8;
"S \NAC"
BN"7"20;
%"TAP"
"1","(-5550,2675)","2","mstr_standard","I26";
;
HDL_TAP"TRUE"
BODY_TYPE"PLUMBING"
CDS_LIB"mstr_standard";
"B \NAC \NWC"6;
"S \NAC"
BN"9"34;
%"TAP"
"1","(-5550,2625)","2","mstr_standard","I27";
;
HDL_TAP"TRUE"
BODY_TYPE"PLUMBING"
CDS_LIB"mstr_standard";
"B \NAC \NWC"6;
"S \NAC"
BN"8"33;
%"TAP"
"1","(-5550,2725)","2","mstr_standard","I28";
;
HDL_TAP"TRUE"
BODY_TYPE"PLUMBING"
CDS_LIB"mstr_standard";
"B \NAC \NWC"6;
"S \NAC"
BN"10"35;
%"TAP"
"1","(-5550,2775)","2","mstr_standard","I29";
;
HDL_TAP"TRUE"
BODY_TYPE"PLUMBING"
CDS_LIB"mstr_standard";
"B \NAC \NWC"6;
"S \NAC"
BN"11"36;
%"TAP"
"1","(-5400,2875)","2","mstr_standard","I30";
;
HDL_TAP"TRUE"
BODY_TYPE"PLUMBING"
CDS_LIB"mstr_standard";
"B \NAC \NWC"5;
"S \NAC"
BN"8"21;
%"TAP"
"1","(-5400,2925)","2","mstr_standard","I31";
;
HDL_TAP"TRUE"
BODY_TYPE"PLUMBING"
CDS_LIB"mstr_standard";
"B \NAC \NWC"5;
"S \NAC"
BN"9"22;
%"TAP"
"1","(-5400,2975)","2","mstr_standard","I32";
;
HDL_TAP"TRUE"
BODY_TYPE"PLUMBING"
CDS_LIB"mstr_standard";
"B \NAC \NWC"5;
"S \NAC"
BN"10"23;
%"TAP"
"1","(-5400,3025)","2","mstr_standard","I33";
;
HDL_TAP"TRUE"
BODY_TYPE"PLUMBING"
CDS_LIB"mstr_standard";
"B \NAC \NWC"5;
"S \NAC"
BN"11"24;
%"TAP"
"1","(-5550,3175)","2","mstr_standard","I34";
;
HDL_TAP"TRUE"
BODY_TYPE"PLUMBING"
CDS_LIB"mstr_standard";
"B \NAC \NWC"6;
"S \NAC"
BN"13"38;
%"TAP"
"1","(-5550,3375)","2","mstr_standard","I35";
;
HDL_TAP"TRUE"
BODY_TYPE"PLUMBING"
CDS_LIB"mstr_standard";
"B \NAC \NWC"6;
"S \NAC"
BN"12"25;
%"TAP"
"1","(-5550,3225)","2","mstr_standard","I36";
;
HDL_TAP"TRUE"
BODY_TYPE"PLUMBING"
CDS_LIB"mstr_standard";
"B \NAC \NWC"6;
"S \NAC"
BN"14"39;
%"TAP"
"1","(-5550,3275)","2","mstr_standard","I37";
;
HDL_TAP"TRUE"
BODY_TYPE"PLUMBING"
CDS_LIB"mstr_standard";
"B \NAC \NWC"6;
"S \NAC"
BN"15"40;
%"TAP"
"1","(-5400,3125)","2","mstr_standard","I38";
;
HDL_TAP"TRUE"
BODY_TYPE"PLUMBING"
CDS_LIB"mstr_standard";
"B \NAC \NWC"5;
"S \NAC"
BN"12"37;
%"TAP"
"1","(-5400,3425)","2","mstr_standard","I39";
;
HDL_TAP"TRUE"
BODY_TYPE"PLUMBING"
CDS_LIB"mstr_standard";
"B \NAC \NWC"5;
"S \NAC"
BN"13"26;
%"TAP"
"1","(-5400,3525)","2","mstr_standard","I40";
;
HDL_TAP"TRUE"
BODY_TYPE"PLUMBING"
CDS_LIB"mstr_standard";
"B \NAC \NWC"5;
"S \NAC"
BN"15"28;
%"TAP"
"1","(-5400,3475)","2","mstr_standard","I41";
;
HDL_TAP"TRUE"
BODY_TYPE"PLUMBING"
CDS_LIB"mstr_standard";
"B \NAC \NWC"5;
"S \NAC"
BN"14"27;
%"TAP"
"1","(-2775,1675)","0","mstr_standard","I42";
;
HDL_TAP"TRUE"
BODY_TYPE"PLUMBING"
CDS_LIB"mstr_standard";
"B \NAC \NWC"2;
"S \NAC"
BN"1"46;
%"TAP"
"1","(-2775,1625)","0","mstr_standard","I43";
;
HDL_TAP"TRUE"
BODY_TYPE"PLUMBING"
CDS_LIB"mstr_standard";
"B \NAC \NWC"2;
"S \NAC"
BN"0"45;
%"TAP"
"1","(-2775,1725)","0","mstr_standard","I44";
;
HDL_TAP"TRUE"
BODY_TYPE"PLUMBING"
CDS_LIB"mstr_standard";
"B \NAC \NWC"2;
"S \NAC"
BN"2"47;
%"TAP"
"1","(-2775,1775)","0","mstr_standard","I45";
;
HDL_TAP"TRUE"
BODY_TYPE"PLUMBING"
CDS_LIB"mstr_standard";
"B \NAC \NWC"2;
"S \NAC"
BN"3"48;
%"TAP"
"1","(-2925,1875)","0","mstr_standard","I46";
;
HDL_TAP"TRUE"
BODY_TYPE"PLUMBING"
CDS_LIB"mstr_standard";
"B \NAC \NWC"4;
"S \NAC"
BN"0"41;
%"TAP"
"1","(-2925,1975)","0","mstr_standard","I47";
;
HDL_TAP"TRUE"
BODY_TYPE"PLUMBING"
CDS_LIB"mstr_standard";
"B \NAC \NWC"4;
"S \NAC"
BN"2"43;
%"TAP"
"1","(-2925,1925)","0","mstr_standard","I48";
;
HDL_TAP"TRUE"
BODY_TYPE"PLUMBING"
CDS_LIB"mstr_standard";
"B \NAC \NWC"4;
"S \NAC"
BN"1"42;
%"TAP"
"1","(-2925,2025)","0","mstr_standard","I49";
;
HDL_TAP"TRUE"
BODY_TYPE"PLUMBING"
CDS_LIB"mstr_standard";
"B \NAC \NWC"4;
"S \NAC"
BN"3"44;
%"TAP"
"1","(-2775,2125)","0","mstr_standard","I50";
;
HDL_TAP"TRUE"
BODY_TYPE"PLUMBING"
CDS_LIB"mstr_standard";
"B \NAC \NWC"2;
"S \NAC"
BN"4"61;
%"TAP"
"1","(-2775,2175)","0","mstr_standard","I51";
;
HDL_TAP"TRUE"
BODY_TYPE"PLUMBING"
CDS_LIB"mstr_standard";
"B \NAC \NWC"2;
"S \NAC"
BN"5"62;
%"TAP"
"1","(-2775,2225)","0","mstr_standard","I52";
;
HDL_TAP"TRUE"
BODY_TYPE"PLUMBING"
CDS_LIB"mstr_standard";
"B \NAC \NWC"2;
"S \NAC"
BN"6"63;
%"TAP"
"1","(-2775,2275)","0","mstr_standard","I53";
;
HDL_TAP"TRUE"
BODY_TYPE"PLUMBING"
CDS_LIB"mstr_standard";
"B \NAC \NWC"2;
"S \NAC"
BN"7"64;
%"TAP"
"1","(-2925,2425)","0","mstr_standard","I54";
;
HDL_TAP"TRUE"
BODY_TYPE"PLUMBING"
CDS_LIB"mstr_standard";
"B \NAC \NWC"4;
"S \NAC"
BN"5"50;
%"TAP"
"1","(-2925,2375)","0","mstr_standard","I55";
;
HDL_TAP"TRUE"
BODY_TYPE"PLUMBING"
CDS_LIB"mstr_standard";
"B \NAC \NWC"4;
"S \NAC"
BN"4"49;
%"TAP"
"1","(-2925,2475)","0","mstr_standard","I56";
;
HDL_TAP"TRUE"
BODY_TYPE"PLUMBING"
CDS_LIB"mstr_standard";
"B \NAC \NWC"4;
"S \NAC"
BN"6"51;
%"TAP"
"1","(-2925,2525)","0","mstr_standard","I57";
;
HDL_TAP"TRUE"
BODY_TYPE"PLUMBING"
CDS_LIB"mstr_standard";
"B \NAC \NWC"4;
"S \NAC"
BN"7"52;
%"TAP"
"1","(-2775,2625)","0","mstr_standard","I58";
;
HDL_TAP"TRUE"
BODY_TYPE"PLUMBING"
CDS_LIB"mstr_standard";
"B \NAC \NWC"1;
"S \NAC"
BN"8"65;
%"TAP"
"1","(-2775,2725)","0","mstr_standard","I59";
;
HDL_TAP"TRUE"
BODY_TYPE"PLUMBING"
CDS_LIB"mstr_standard";
"B \NAC \NWC"1;
"S \NAC"
BN"10"67;
%"TAP"
"1","(-2775,2675)","0","mstr_standard","I60";
;
HDL_TAP"TRUE"
BODY_TYPE"PLUMBING"
CDS_LIB"mstr_standard";
"B \NAC \NWC"1;
"S \NAC"
BN"9"66;
%"TAP"
"1","(-2775,2775)","0","mstr_standard","I61";
;
HDL_TAP"TRUE"
BODY_TYPE"PLUMBING"
CDS_LIB"mstr_standard";
"B \NAC \NWC"1;
"S \NAC"
BN"11"68;
%"TAP"
"1","(-2925,2925)","0","mstr_standard","I62";
;
HDL_TAP"TRUE"
BODY_TYPE"PLUMBING"
CDS_LIB"mstr_standard";
"B \NAC \NWC"3;
"S \NAC"
BN"9"54;
%"TAP"
"1","(-2925,2875)","0","mstr_standard","I63";
;
HDL_TAP"TRUE"
BODY_TYPE"PLUMBING"
CDS_LIB"mstr_standard";
"B \NAC \NWC"3;
"S \NAC"
BN"8"53;
%"TAP"
"1","(-2925,3025)","0","mstr_standard","I64";
;
HDL_TAP"TRUE"
BODY_TYPE"PLUMBING"
CDS_LIB"mstr_standard";
"B \NAC \NWC"3;
"S \NAC"
BN"11"56;
%"TAP"
"1","(-2925,2975)","0","mstr_standard","I65";
;
HDL_TAP"TRUE"
BODY_TYPE"PLUMBING"
CDS_LIB"mstr_standard";
"B \NAC \NWC"3;
"S \NAC"
BN"10"55;
%"TAP"
"1","(-2775,3125)","0","mstr_standard","I66";
;
HDL_TAP"TRUE"
BODY_TYPE"PLUMBING"
CDS_LIB"mstr_standard";
"B \NAC \NWC"1;
"S \NAC"
BN"12"69;
%"TAP"
"1","(-2775,3175)","0","mstr_standard","I67";
;
HDL_TAP"TRUE"
BODY_TYPE"PLUMBING"
CDS_LIB"mstr_standard";
"B \NAC \NWC"1;
"S \NAC"
BN"13"70;
%"TAP"
"1","(-2775,3225)","0","mstr_standard","I68";
;
HDL_TAP"TRUE"
BODY_TYPE"PLUMBING"
CDS_LIB"mstr_standard";
"B \NAC \NWC"1;
"S \NAC"
BN"14"71;
%"TAP"
"1","(-2775,3275)","0","mstr_standard","I69";
;
HDL_TAP"TRUE"
BODY_TYPE"PLUMBING"
CDS_LIB"mstr_standard";
"B \NAC \NWC"1;
"S \NAC"
BN"15"72;
%"TAP"
"1","(-2925,3425)","0","mstr_standard","I70";
;
HDL_TAP"TRUE"
BODY_TYPE"PLUMBING"
CDS_LIB"mstr_standard";
"B \NAC \NWC"3;
"S \NAC"
BN"13"58;
%"TAP"
"1","(-2925,3375)","0","mstr_standard","I71";
;
HDL_TAP"TRUE"
BODY_TYPE"PLUMBING"
CDS_LIB"mstr_standard";
"B \NAC \NWC"3;
"S \NAC"
BN"12"57;
%"TAP"
"1","(-2925,3475)","0","mstr_standard","I72";
;
HDL_TAP"TRUE"
BODY_TYPE"PLUMBING"
CDS_LIB"mstr_standard";
"B \NAC \NWC"3;
"S \NAC"
BN"14"59;
%"TAP"
"1","(-2925,3525)","0","mstr_standard","I73";
;
HDL_TAP"TRUE"
BODY_TYPE"PLUMBING"
CDS_LIB"mstr_standard";
"B \NAC \NWC"3;
"S \NAC"
BN"15"60;
%"SKX_EXT_B"
"12","(-4125,2575)","0","chpset_lib","I84";
;
CDS_SEC"12"
CDS_LOCATION"U2D1"
SEC"12"
CDS_LIB"chpset_lib"
SEC_TYPE"BGA1"
PACK_TYPE"BGA1"
MATERIAL"IC"
PART_NUMBER"TBD"
LOCATION"U2D1";
"PE3_TX_DP<0>"
$PN"EC14"41;
"PE3_TX_DP<1>"
$PN"ED13"42;
"PE3_TX_DP<2>"
$PN"EB11"43;
"PE3_TX_DP<3>"
$PN"EA10"44;
"PE3_TX_DP<4>"
$PN"DY9"49;
"PE3_TX_DP<5>"
$PN"DV9"50;
"PE3_TX_DP<6>"
$PN"DT9"51;
"PE3_TX_DP<7>"
$PN"DP7"52;
"PE3_TX_DP<8>"
$PN"DN6"53;
"PE3_TX_DP<9>"
$PN"DM5"54;
"PE3_TX_DP<10>"
$PN"DK5"55;
"PE3_TX_DP<11>"
$PN"DH5"56;
"PE3_TX_DP<12>"
$PN"DG6"57;
"PE3_TX_DP<13>"
$PN"DC6"58;
"PE3_TX_DP<14>"
$PN"DA4"59;
"PE3_TX_DP<15>"
$PN"CV5"60;
"PE3_TX_DN<0>"
$PN"EE14"45;
"PE3_TX_DN<1>"
$PN"EE12"46;
"PE3_TX_DN<2>"
$PN"EC12"47;
"PE3_TX_DN<3>"
$PN"DY11"48;
"PE3_TX_DN<4>"
$PN"EB9"61;
"PE3_TX_DN<5>"
$PN"DW10"62;
"PE3_TX_DN<6>"
$PN"DU8"63;
"PE3_TX_DN<7>"
$PN"DR8"64;
"PE3_TX_DN<8>"
$PN"DM7"65;
"PE3_TX_DN<9>"
$PN"DP5"66;
"PE3_TX_DN<10>"
$PN"DL6"67;
"PE3_TX_DN<11>"
$PN"DJ4"68;
"PE3_TX_DN<12>"
$PN"DJ6"69;
"PE3_TX_DN<13>"
$PN"DD5"70;
"PE3_TX_DN<14>"
$PN"DB5"71;
"PE3_TX_DN<15>"
$PN"CY5"72;
"PE3_RX_DP<0>"
$PN"DY17"9;
"PE3_RX_DP<1>"
$PN"DU18"10;
"PE3_RX_DP<2>"
$PN"DV17"11;
"PE3_RX_DP<3>"
$PN"DR18"12;
"PE3_RX_DP<4>"
$PN"DN16"17;
"PE3_RX_DP<5>"
$PN"DP15"18;
"PE3_RX_DP<6>"
$PN"DM13"19;
"PE3_RX_DP<7>"
$PN"DJ14"20;
"PE3_RX_DP<8>"
$PN"DK13"21;
"PE3_RX_DP<9>"
$PN"DH11"22;
"PE3_RX_DP<10>"
$PN"DE12"23;
"PE3_RX_DP<11>"
$PN"DF11"24;
"PE3_RX_DP<12>"
$PN"DC12"25;
"PE3_RX_DP<13>"
$PN"DA12"26;
"PE3_RX_DP<14>"
$PN"CW10"27;
"PE3_RX_DP<15>"
$PN"CU10"28;
"PE3_RX_DN<0>"
$PN"EA18"13;
"PE3_RX_DN<1>"
$PN"DW18"14;
"PE3_RX_DN<2>"
$PN"DW16"15;
"PE3_RX_DN<3>"
$PN"DT19"16;
"PE3_RX_DN<4>"
$PN"DR16"29;
"PE3_RX_DN<5>"
$PN"DR14"30;
"PE3_RX_DN<6>"
$PN"DN14"31;
"PE3_RX_DN<7>"
$PN"DL14"32;
"PE3_RX_DN<8>"
$PN"DL12"33;
"PE3_RX_DN<9>"
$PN"DJ12"34;
"PE3_RX_DN<10>"
$PN"DG12"35;
"PE3_RX_DN<11>"
$PN"DG10"36;
"PE3_RX_DN<12>"
$PN"DD13"37;
"PE3_RX_DN<13>"
$PN"DB11"38;
"PE3_RX_DN<14>"
$PN"CY11"39;
"PE3_RX_DN<15>"
$PN"CV9"40;
END.
